# S9S_MB_2U (Grand Teton) — schematic netlist excerpt (pin names and nets, part order shuffled) for the footprints in the layout excerpt that follows; sources: Cadence DE-HDL packaged netlist, KiCad conversion of 03242023_DA0F0TMBIJ0_F0T_Motherboard_J_brd_V01_OCP.brd

R4767  Q_RES  49.9 1% CHIP  pkg 0402LF  page 191 : A = HP_E1S_0_P3V3_PWRGD ; B = HP_E1S_0_P3V3_PWRGD_PLD
C885  Q_CAP_DIFFBUS  DIFF BUS_0.22UF 6.3V 20% X6S  pkg C0201  page 174 : \1\ = P5E_CPU0_PE3_TX_C_DP<8> ; \2\ = P5E_CPU0_PE3_TX_DP<8>
PC1254  Q_CAP  0.1UF 25V 10% X7R  pkg 0402  page 281 : A = PVPP_HBM_CPU0 ; B = GND

(kicad_pcb
	(version 20260206)
	(generator "pcbnew")
	(generator_version "10.0")
	(general
		(thickness 1.6)
		(legacy_teardrops no)
	)
	(paper "A4")
	(title_block
		(title "03242023_DA0F0TMBIJ0_F0T_Motherboard_J_brd_V01_OCP.brd")
		(comment 1 "Grand Teton / footprints 1778-1780 of 6105")
	)
	(layers
		(0 "F.Cu" signal "TOP")
		(4 "In1.Cu" signal "GND")
		(6 "In2.Cu" signal "IN1")
		(8 "In3.Cu" signal "GND1")
		(10 "In4.Cu" signal "IN2")
		(12 "In5.Cu" signal "GND2")
		(14 "In6.Cu" signal "IN3")
		(16 "In7.Cu" signal "GND3")
		(18 "In8.Cu" signal "VCC")
		(20 "In9.Cu" signal "VCC1")
		(22 "In10.Cu" signal "GND4")
		(24 "In11.Cu" signal "IN4")
		(26 "In12.Cu" signal "GND5")
		(28 "In13.Cu" signal "IN5")
		(30 "In14.Cu" signal "GND6")
		(32 "In15.Cu" signal "IN6")
		(34 "In16.Cu" signal "GND7")
		(2 "B.Cu" signal "BOTTOM")
		(9 "F.Adhes" user "F.Adhesive")
		(11 "B.Adhes" user "B.Adhesive")
		(13 "F.Paste" user "Package Geometry/Pastemask Top")
		(15 "B.Paste" user "Package Geometry/Pastemask Bottom")
		(5 "F.SilkS" user "Ref Des/Silkscreen Top")
		(7 "B.SilkS" user "Ref Des/Silkscreen Bottom")
		(1 "F.Mask" user "Board Geometry/Soldermask Top")
		(3 "B.Mask" user "Board Geometry/Soldermask Bottom")
		(17 "Dwgs.User" user "User.Drawings")
		(19 "Cmts.User" user "User.Comments")
		(21 "Eco1.User" user "User.Eco1")
		(23 "Eco2.User" user "User.Eco2")
		(25 "Edge.Cuts" user "Board Geometry/Outline")
		(27 "Margin" user)
		(31 "F.CrtYd" user "Package Geometry/Place Bound Top")
		(29 "B.CrtYd" user "Package Geometry/Place Bound Bottom")
		(35 "F.Fab" user "Ref Des/Assembly Top")
		(33 "B.Fab" user "Ref Des/Assembly Bottom")
	)
	(footprint ""
		(layer "F.Cu")
		(at 217.47226 -47.90694 90)
		(property "Reference" "R4767"
			(at 0 0 90)
			(layer "F.SilkS")
			(hide yes)
			(effects
				(font
					(size 1.27 1.27)
				)
			)
		)
		(property "Value" ""
			(at 0 0 90)
			(layer "F.Fab")
			(effects
				(font
					(size 1.27 1.27)
				)
			)
		)
		(duplicate_pad_numbers_are_jumpers no)
		(fp_line
			(start 0.7874 -0.4064)
			(end 0.7874 0.4064)
			(stroke
				(width 0.1524)
				(type default)
			)
			(layer "F.SilkS")
		)
		(fp_line
			(start -0.7874 -0.4064)
			(end 0.7874 -0.4064)
			(stroke
				(width 0.1524)
				(type default)
			)
			(layer "F.SilkS")
		)
		(fp_line
			(start 0.7874 0.4064)
			(end -0.7874 0.4064)
			(stroke
				(width 0.1524)
				(type default)
			)
			(layer "F.SilkS")
		)
		(fp_line
			(start -0.7874 0.4064)
			(end -0.7874 -0.4064)
			(stroke
				(width 0.1524)
				(type default)
			)
			(layer "F.SilkS")
		)
		(fp_line
			(start -0.12065 -0.305054)
			(end -0.12065 -0.2794)
			(stroke
				(width 0.1)
				(type default)
			)
			(layer "F.Fab")
		)
		(fp_line
			(start -0.67945 -0.305054)
			(end -0.12065 -0.305054)
			(stroke
				(width 0.1)
				(type default)
			)
			(layer "F.Fab")
		)
		(fp_line
			(start 0.67945 -0.3048)
			(end 0.67945 0.3048)
			(stroke
				(width 0.1)
				(type default)
			)
			(layer "F.Fab")
		)
		(fp_line
			(start 0.12065 -0.3048)
			(end 0.67945 -0.3048)
			(stroke
				(width 0.1)
				(type default)
			)
			(layer "F.Fab")
		)
		(fp_line
			(start 0.12065 -0.2794)
			(end 0.12065 -0.3048)
			(stroke
				(width 0.1)
				(type default)
			)
			(layer "F.Fab")
		)
		(fp_line
			(start -0.12065 -0.2794)
			(end 0.12065 -0.2794)
			(stroke
				(width 0.1)
				(type default)
			)
			(layer "F.Fab")
		)
		(fp_line
			(start 0.120396 0.2794)
			(end -0.12065 0.2794)
			(stroke
				(width 0.1)
				(type default)
			)
			(layer "F.Fab")
		)
		(fp_line
			(start -0.12065 0.2794)
			(end -0.12065 0.3048)
			(stroke
				(width 0.1)
				(type default)
			)
			(layer "F.Fab")
		)
		(fp_line
			(start 0.67945 0.3048)
			(end 0.120396 0.3048)
			(stroke
				(width 0.1)
				(type default)
			)
			(layer "F.Fab")
		)
		(fp_line
			(start 0.120396 0.3048)
			(end 0.120396 0.2794)
			(stroke
				(width 0.1)
				(type default)
			)
			(layer "F.Fab")
		)
		(fp_line
			(start -0.12065 0.3048)
			(end -0.67945 0.3048)
			(stroke
				(width 0.1)
				(type default)
			)
			(layer "F.Fab")
		)
		(fp_line
			(start -0.67945 0.3048)
			(end -0.67945 -0.305054)
			(stroke
				(width 0.1)
				(type default)
			)
			(layer "F.Fab")
		)
		(pad "1" smd circle
			(at -0.40005 0 90)
			(size 0 0)
			(layers "F.Cu" "F.Mask" "F.Paste")
			(net "HP_E1S_0_P3V3_PWRGD")
		)
		(pad "2" smd circle
			(at 0.40005 0 90)
			(size 0 0)
			(layers "F.Cu" "F.Mask" "F.Paste")
			(net "HP_E1S_0_P3V3_PWRGD_PLD")
		)
	)
	(footprint ""
		(layer "F.Cu")
		(at 369.554252 -366.764062 -90)
		(property "Reference" "PC1254"
			(at 0 0 270)
			(layer "F.SilkS")
			(hide yes)
			(effects
				(font
					(size 1.27 1.27)
				)
			)
		)
		(property "Value" ""
			(at 0 0 270)
			(layer "F.Fab")
			(effects
				(font
					(size 1.27 1.27)
				)
			)
		)
		(duplicate_pad_numbers_are_jumpers no)
		(fp_line
			(start -0.7874 0.4064)
			(end -0.7874 -0.4064)
			(stroke
				(width 0.1524)
				(type default)
			)
			(layer "F.SilkS")
		)
		(fp_line
			(start 0.7874 0.4064)
			(end -0.7874 0.4064)
			(stroke
				(width 0.1524)
				(type default)
			)
			(layer "F.SilkS")
		)
		(fp_line
			(start -0.7874 -0.4064)
			(end 0.7874 -0.4064)
			(stroke
				(width 0.1524)
				(type default)
			)
			(layer "F.SilkS")
		)
		(fp_line
			(start 0.7874 -0.4064)
			(end 0.7874 0.4064)
			(stroke
				(width 0.1524)
				(type default)
			)
			(layer "F.SilkS")
		)
		(fp_line
			(start -0.67945 0.3048)
			(end -0.67945 -0.305054)
			(stroke
				(width 0.1)
				(type default)
			)
			(layer "F.Fab")
		)
		(fp_line
			(start -0.12065 0.3048)
			(end -0.67945 0.3048)
			(stroke
				(width 0.1)
				(type default)
			)
			(layer "F.Fab")
		)
		(fp_line
			(start 0.120396 0.3048)
			(end 0.120396 0.2794)
			(stroke
				(width 0.1)
				(type default)
			)
			(layer "F.Fab")
		)
		(fp_line
			(start 0.67945 0.3048)
			(end 0.120396 0.3048)
			(stroke
				(width 0.1)
				(type default)
			)
			(layer "F.Fab")
		)
		(fp_line
			(start -0.12065 0.2794)
			(end -0.12065 0.3048)
			(stroke
				(width 0.1)
				(type default)
			)
			(layer "F.Fab")
		)
		(fp_line
			(start 0.120396 0.2794)
			(end -0.12065 0.2794)
			(stroke
				(width 0.1)
				(type default)
			)
			(layer "F.Fab")
		)
		(fp_line
			(start -0.12065 -0.2794)
			(end 0.12065 -0.2794)
			(stroke
				(width 0.1)
				(type default)
			)
			(layer "F.Fab")
		)
		(fp_line
			(start 0.12065 -0.2794)
			(end 0.12065 -0.3048)
			(stroke
				(width 0.1)
				(type default)
			)
			(layer "F.Fab")
		)
		(fp_line
			(start 0.12065 -0.3048)
			(end 0.67945 -0.3048)
			(stroke
				(width 0.1)
				(type default)
			)
			(layer "F.Fab")
		)
		(fp_line
			(start 0.67945 -0.3048)
			(end 0.67945 0.3048)
			(stroke
				(width 0.1)
				(type default)
			)
			(layer "F.Fab")
		)
		(fp_line
			(start -0.67945 -0.305054)
			(end -0.12065 -0.305054)
			(stroke
				(width 0.1)
				(type default)
			)
			(layer "F.Fab")
		)
		(fp_line
			(start -0.12065 -0.305054)
			(end -0.12065 -0.2794)
			(stroke
				(width 0.1)
				(type default)
			)
			(layer "F.Fab")
		)
		(pad "1" smd circle
			(at -0.40005 0 270)
			(size 0 0)
			(layers "F.Cu" "F.Mask" "F.Paste")
			(net "PVPP_HBM_CPU0")
		)
		(pad "2" smd circle
			(at 0.40005 0 270)
			(size 0 0)
			(layers "F.Cu" "F.Mask" "F.Paste")
			(net "GND")
		)
	)
	(footprint ""
		(layer "F.Cu")
		(at 395.10081 -408.517344 -90)
		(property "Reference" "C885"
			(at 0 0 270)
			(layer "F.SilkS")
			(hide yes)
			(effects
				(font
					(size 1.27 1.27)
				)
			)
		)
		(property "Value" ""
			(at 0 0 270)
			(layer "F.Fab")
			(effects
				(font
					(size 1.27 1.27)
				)
			)
		)
		(duplicate_pad_numbers_are_jumpers no)
		(fp_line
			(start -0.299974 0.150114)
			(end -0.299974 -0.150114)
			(stroke
				(width 0.1)
				(type default)
			)
			(layer "F.Fab")
		)
		(fp_line
			(start 0.299974 0.150114)
			(end -0.299974 0.150114)
			(stroke
				(width 0.1)
				(type default)
			)
			(layer "F.Fab")
		)
		(fp_line
			(start -0.299974 -0.150114)
			(end 0.299974 -0.150114)
			(stroke
				(width 0.1)
				(type default)
			)
			(layer "F.Fab")
		)
		(fp_line
			(start 0.299974 -0.150114)
			(end 0.299974 0.150114)
			(stroke
				(width 0.1)
				(type default)
			)
			(layer "F.Fab")
		)
		(pad "1" smd rect
			(at -0.2667 0 270)
			(size 0.3048 0.381)
			(layers "F.Cu" "F.Mask" "F.Paste")
			(net "P5E_CPU0_PE3_TX_C_DP<8>")
		)
		(pad "2" smd rect
			(at 0.2667 0 270)
			(size 0.3048 0.381)
			(layers "F.Cu" "F.Mask" "F.Paste")
			(net "P5E_CPU0_PE3_TX_DP<8>")
		)
	)
)
